# BASEBOARD_FAB2 (Tioga Pass) — schematic netlist excerpt (pin names and nets, part order shuffled) for the footprints in the layout excerpt that follows; sources: Cadence DE-HDL packaged netlist, KiCad conversion of Wiwynn_Tioga_Pass_MB.brd

C4D25  CAP_A  1.0UF 6.3V 10% X6S  pkg 0402V  page 201 : A = VR_PVCCIN_CPU0_VD12 ; B = GND
R7D34  RES  33.2 1% CHIP  pkg 0402  page 92 : A = FM_CPU0_THERMTRIP_LVT3_R_N ; B = FM_CPU0_THERMTRIP_LVT3_N
CT13  CAP_A  0.1UF 16V 10% X7R  pkg 0402V  page 209 : A = VR_PVCCIN_CPU1_AIREF5 ; B = GND

(kicad_pcb
	(version 20260206)
	(generator "pcbnew")
	(generator_version "10.0")
	(general
		(thickness 1.6)
		(legacy_teardrops no)
	)
	(paper "A4")
	(title_block
		(title "Wiwynn_Tioga_Pass_MB.brd")
		(comment 1 "Tioga Pass / footprints 1896-1898 of 4770")
	)
	(layers
		(0 "F.Cu" signal "TOP")
		(4 "In1.Cu" signal "L2GND")
		(6 "In2.Cu" signal "L3")
		(8 "In3.Cu" signal "L4GND")
		(10 "In4.Cu" signal "L5")
		(12 "In5.Cu" signal "L6GND")
		(14 "In6.Cu" signal "L7VCC")
		(16 "In7.Cu" signal "L8VCC")
		(18 "In8.Cu" signal "L9GND")
		(20 "In9.Cu" signal "L10")
		(22 "In10.Cu" signal "L11GND")
		(24 "In11.Cu" signal "L12")
		(26 "In12.Cu" signal "L13GND")
		(2 "B.Cu" signal "BOTTOM")
		(9 "F.Adhes" user "F.Adhesive")
		(11 "B.Adhes" user "B.Adhesive")
		(13 "F.Paste" user "Package Geometry/Pastemask Top")
		(15 "B.Paste" user "Package Geometry/Pastemask Bottom")
		(5 "F.SilkS" user "Ref Des/Silkscreen Top")
		(7 "B.SilkS" user "Ref Des/Silkscreen Bottom")
		(1 "F.Mask" user "Board Geometry/Soldermask Top")
		(3 "B.Mask" user "Board Geometry/Soldermask Bottom")
		(17 "Dwgs.User" user "User.Drawings")
		(19 "Cmts.User" user "User.Comments")
		(21 "Eco1.User" user "User.Eco1")
		(23 "Eco2.User" user "User.Eco2")
		(25 "Edge.Cuts" user "Board Geometry/Outline")
		(27 "Margin" user)
		(31 "F.CrtYd" user "Package Geometry/Place Bound Top")
		(29 "B.CrtYd" user "Package Geometry/Place Bound Bottom")
		(35 "F.Fab" user "Ref Des/Assembly Top")
		(33 "B.Fab" user "Ref Des/Assembly Bottom")
	)
	(footprint ""
		(layer "F.Cu")
		(at 394.6525 -75.819 90)
		(property "Reference" "R7D34"
			(at 0 0 90)
			(layer "F.SilkS")
			(hide yes)
			(effects
				(font
					(size 1.27 1.27)
				)
			)
		)
		(property "Value" ""
			(at 0 0 90)
			(layer "F.Fab")
			(effects
				(font
					(size 1.27 1.27)
				)
			)
		)
		(duplicate_pad_numbers_are_jumpers no)
		(fp_poly
			(pts
				(xy -0.2794 -0.1016) (xy 0.2794 -0.1016) (xy 0.2794 0.9906) (xy -0.2794 0.9906)
			)
			(stroke
				(width 0)
				(type default)
			)
			(fill no)
			(layer "F.CrtYd")
		)
		(fp_line
			(start 0.2794 -0.1016)
			(end -0.2794 -0.1016)
			(stroke
				(width 0.1)
				(type default)
			)
			(layer "F.Fab")
		)
		(fp_line
			(start -0.2794 -0.1016)
			(end -0.2794 0.9906)
			(stroke
				(width 0.1)
				(type default)
			)
			(layer "F.Fab")
		)
		(fp_line
			(start 0.2794 0.9906)
			(end 0.2794 -0.1016)
			(stroke
				(width 0.1)
				(type default)
			)
			(layer "F.Fab")
		)
		(fp_line
			(start -0.2794 0.9906)
			(end 0.2794 0.9906)
			(stroke
				(width 0.1)
				(type default)
			)
			(layer "F.Fab")
		)
		(pad "1" smd rect
			(at 0 0 90)
			(size 0.508 0.508)
			(layers "F.Cu" "F.Mask" "F.Paste")
			(net "FM_CPU0_THERMTRIP_LVT3_R_N")
		)
		(pad "2" smd rect
			(at 0 0.889 90)
			(size 0.508 0.508)
			(layers "F.Cu" "F.Mask" "F.Paste")
			(net "FM_CPU0_THERMTRIP_LVT3_N")
		)
		(zone
			(layer "F.Cu")
			(hatch none 0.5)
			(connect_pads
				(clearance 0)
			)
			(min_thickness 0.25)
			(keepout
				(tracks allowed)
				(vias not_allowed)
				(pads allowed)
				(copperpour not_allowed)
				(footprints allowed)
			)
			(placement
				(enabled no)
				(sheetname "")
			)
			(fill
				(thermal_gap 0.5)
				(thermal_bridge_width 0.5)
				(island_removal_mode 0)
			)
			(polygon
				(pts
					(xy 394.9065 -75.565) (xy 394.9065 -76.073) (xy 395.2875 -76.073) (xy 395.2875 -75.565)
				)
			)
		)
		(zone
			(layer "F.Cu")
			(hatch none 0.5)
			(connect_pads
				(clearance 0)
			)
			(min_thickness 0.25)
			(keepout
				(tracks not_allowed)
				(vias allowed)
				(pads allowed)
				(copperpour not_allowed)
				(footprints allowed)
			)
			(placement
				(enabled no)
				(sheetname "")
			)
			(fill
				(thermal_gap 0.5)
				(thermal_bridge_width 0.5)
				(island_removal_mode 0)
			)
			(polygon
				(pts
					(xy 395.2875 -75.565) (xy 395.2875 -76.073) (xy 394.9065 -76.073) (xy 394.9065 -75.565)
				)
			)
		)
	)
	(footprint ""
		(layer "F.Cu")
		(at 180.381148 -72.96785 -90)
		(property "Reference" "C4D25"
			(at 0 0 270)
			(layer "F.SilkS")
			(hide yes)
			(effects
				(font
					(size 1.27 1.27)
				)
			)
		)
		(property "Value" ""
			(at 0 0 270)
			(layer "F.Fab")
			(effects
				(font
					(size 1.27 1.27)
				)
			)
		)
		(duplicate_pad_numbers_are_jumpers no)
		(fp_poly
			(pts
				(xy 0.3048 -0.1016) (xy 0.3048 0.9906) (xy -0.3048 0.9906) (xy -0.3048 -0.1016)
			)
			(stroke
				(width 0)
				(type default)
			)
			(fill no)
			(layer "F.CrtYd")
		)
		(fp_line
			(start -0.3048 0.9906)
			(end 0.3048 0.9906)
			(stroke
				(width 0.1)
				(type default)
			)
			(layer "F.Fab")
		)
		(fp_line
			(start 0.3048 0.9906)
			(end 0.3048 -0.1016)
			(stroke
				(width 0.1)
				(type default)
			)
			(layer "F.Fab")
		)
		(fp_line
			(start -0.3048 -0.1016)
			(end -0.3048 0.9906)
			(stroke
				(width 0.1)
				(type default)
			)
			(layer "F.Fab")
		)
		(fp_line
			(start 0.3048 -0.1016)
			(end -0.3048 -0.1016)
			(stroke
				(width 0.1)
				(type default)
			)
			(layer "F.Fab")
		)
		(pad "1" smd rect
			(at 0 0 270)
			(size 0.508 0.508)
			(layers "F.Cu" "F.Mask" "F.Paste")
			(net "VR_PVCCIN_CPU0_VD12")
		)
		(pad "2" smd rect
			(at 0 0.889 270)
			(size 0.508 0.508)
			(layers "F.Cu" "F.Mask" "F.Paste")
			(net "GND")
		)
		(zone
			(layer "F.Cu")
			(hatch none 0.5)
			(connect_pads
				(clearance 0)
			)
			(min_thickness 0.25)
			(keepout
				(tracks not_allowed)
				(vias allowed)
				(pads allowed)
				(copperpour not_allowed)
				(footprints allowed)
			)
			(placement
				(enabled no)
				(sheetname "")
			)
			(fill
				(thermal_gap 0.5)
				(thermal_bridge_width 0.5)
				(island_removal_mode 0)
			)
			(polygon
				(pts
					(xy 179.746148 -73.22185) (xy 179.746148 -72.71385) (xy 180.127148 -72.71385) (xy 180.127148 -73.22185)
				)
			)
		)
		(zone
			(layer "F.Cu")
			(hatch none 0.5)
			(connect_pads
				(clearance 0)
			)
			(min_thickness 0.25)
			(keepout
				(tracks allowed)
				(vias not_allowed)
				(pads allowed)
				(copperpour not_allowed)
				(footprints allowed)
			)
			(placement
				(enabled no)
				(sheetname "")
			)
			(fill
				(thermal_gap 0.5)
				(thermal_bridge_width 0.5)
				(island_removal_mode 0)
			)
			(polygon
				(pts
					(xy 180.127148 -73.22185) (xy 180.127148 -72.71385) (xy 179.746148 -72.71385) (xy 179.746148 -73.22185)
				)
			)
		)
	)
	(footprint ""
		(layer "F.Cu")
		(at 28.82773 -85.983318 90)
		(property "Reference" "CT13"
			(at 2.28473 -5.9182 0)
			(unlocked yes)
			(layer "F.SilkS")
			(effects
				(font
					(size 0.7874 0.5842)
					(thickness 0.1524)
				)
				(justify left)
			)
		)
		(property "Value" ""
			(at 0 0 90)
			(layer "F.Fab")
			(effects
				(font
					(size 1.27 1.27)
				)
			)
		)
		(duplicate_pad_numbers_are_jumpers no)
		(fp_poly
			(pts
				(xy 0.3048 -0.1016) (xy 0.3048 0.9906) (xy -0.3048 0.9906) (xy -0.3048 -0.1016)
			)
			(stroke
				(width 0)
				(type default)
			)
			(fill no)
			(layer "F.CrtYd")
		)
		(fp_line
			(start 0.3048 -0.1016)
			(end -0.3048 -0.1016)
			(stroke
				(width 0.1)
				(type default)
			)
			(layer "F.Fab")
		)
		(fp_line
			(start -0.3048 -0.1016)
			(end -0.3048 0.9906)
			(stroke
				(width 0.1)
				(type default)
			)
			(layer "F.Fab")
		)
		(fp_line
			(start 0.3048 0.9906)
			(end 0.3048 -0.1016)
			(stroke
				(width 0.1)
				(type default)
			)
			(layer "F.Fab")
		)
		(fp_line
			(start -0.3048 0.9906)
			(end 0.3048 0.9906)
			(stroke
				(width 0.1)
				(type default)
			)
			(layer "F.Fab")
		)
		(pad "1" smd rect
			(at 0 0 90)
			(size 0.508 0.508)
			(layers "F.Cu" "F.Mask" "F.Paste")
			(net "VR_PVCCIN_CPU1_AIREF5")
		)
		(pad "2" smd rect
			(at 0 0.889 90)
			(size 0.508 0.508)
			(layers "F.Cu" "F.Mask" "F.Paste")
			(net "GND")
		)
		(zone
			(layer "F.Cu")
			(hatch none 0.5)
			(connect_pads
				(clearance 0)
			)
			(min_thickness 0.25)
			(keepout
				(tracks allowed)
				(vias not_allowed)
				(pads allowed)
				(copperpour not_allowed)
				(footprints allowed)
			)
			(placement
				(enabled no)
				(sheetname "")
			)
			(fill
				(thermal_gap 0.5)
				(thermal_bridge_width 0.5)
				(island_removal_mode 0)
			)
			(polygon
				(pts
					(xy 29.08173 -85.729318) (xy 29.08173 -86.237318) (xy 29.46273 -86.237318) (xy 29.46273 -85.729318)
				)
			)
		)
		(zone
			(layer "F.Cu")
			(hatch none 0.5)
			(connect_pads
				(clearance 0)
			)
			(min_thickness 0.25)
			(keepout
				(tracks not_allowed)
				(vias allowed)
				(pads allowed)
				(copperpour not_allowed)
				(footprints allowed)
			)
			(placement
				(enabled no)
				(sheetname "")
			)
			(fill
				(thermal_gap 0.5)
				(thermal_bridge_width 0.5)
				(island_removal_mode 0)
			)
			(polygon
				(pts
					(xy 29.46273 -85.729318) (xy 29.46273 -86.237318) (xy 29.08173 -86.237318) (xy 29.08173 -85.729318)
				)
			)
		)
	)
)
